(kicad_pcb
	(version 20260206)
	(generator "pcbnew")
	(generator_version "10.0")
	(general
		(thickness 1.6)
		(legacy_teardrops no)
	)
	(paper "A4")
	(title_block
		(title "Bryce Canyon_F.DPB_16315-1-OCP.brd")
		(comment 1 "Bryce Canyon / footprints 2184-2192 of 2223")
	)
	(layers
		(0 "F.Cu" signal "TOP")
		(4 "In1.Cu" signal "L2GND")
		(6 "In2.Cu" signal "L3")
		(8 "In3.Cu" signal "L4GND")
		(10 "In4.Cu" signal "L5")
		(12 "In5.Cu" signal "L6VCC")
		(14 "In6.Cu" signal "L7VCC")
		(16 "In7.Cu" signal "L8")
		(18 "In8.Cu" signal "L9GND")
		(20 "In9.Cu" signal "L10")
		(22 "In10.Cu" signal "L11GND")
		(2 "B.Cu" signal "BOTTOM")
		(9 "F.Adhes" user "F.Adhesive")
		(11 "B.Adhes" user "B.Adhesive")
		(13 "F.Paste" user "Package Geometry/Pastemask Top")
		(15 "B.Paste" user "Package Geometry/Pastemask Bottom")
		(5 "F.SilkS" user "Ref Des/Silkscreen Top")
		(7 "B.SilkS" user "Ref Des/Silkscreen Bottom")
		(1 "F.Mask" user "Board Geometry/Soldermask Top")
		(3 "B.Mask" user "Board Geometry/Soldermask Bottom")
		(17 "Dwgs.User" user "User.Drawings")
		(19 "Cmts.User" user "User.Comments")
		(21 "Eco1.User" user "User.Eco1")
		(23 "Eco2.User" user "User.Eco2")
		(25 "Edge.Cuts" user "Board Geometry/Outline")
		(27 "Margin" user)
		(31 "F.CrtYd" user "Package Geometry/Place Bound Top")
		(29 "B.CrtYd" user "Package Geometry/Place Bound Bottom")
		(35 "F.Fab" user "Ref Des/Assembly Top")
		(33 "B.Fab" user "Ref Des/Assembly Bottom")
	)
	(footprint ""
		(layer "B.Cu")
		(at 184.00395 -221.880176 -90)
		(property "Reference" "C675"
			(at 0 0 90)
			(layer "B.SilkS")
			(hide yes)
			(effects
				(font
					(size 1.27 1.27)
				)
				(justify mirror)
			)
		)
		(property "Value" "SC3300P50V2KX-1GP"
			(at -1.1811 -2.7051 270)
			(unlocked yes)
			(layer "B.Fab")
			(hide yes)
			(effects
				(font
					(size 1.016 1.016)
					(thickness 0.1524)
				)
				(justify mirror)
			)
		)
		(property "Device Type" "C402H22"
			(at -1.1811 -4.2291 270)
			(unlocked yes)
			(layer "B.Fab")
			(hide yes)
			(effects
				(font
					(size 1.016 1.016)
					(thickness 0.1524)
				)
				(justify mirror)
			)
		)
		(duplicate_pad_numbers_are_jumpers no)
		(fp_rect
			(start 0.4318 0.9525)
			(end -0.4318 -0.9525)
			(stroke
				(width 0)
				(type default)
			)
			(fill no)
			(layer "B.CrtYd")
		)
		(fp_rect
			(start 0.4318 0.9525)
			(end -0.4318 -0.9525)
			(stroke
				(width 0)
				(type default)
			)
			(fill no)
			(layer "B.Fab")
		)
		(pad "1" smd custom
			(at 0 -0.4445 90)
			(size 0.1524 0.1524)
			(layers "B.Cu" "B.Mask" "B.Paste")
			(net "P3V3_STBY_SS")
			(options
				(clearance outline)
				(anchor circle)
			)
			(primitives
				(gr_poly
					(pts
						(arc
							(start 0.3048 0.2032)
							(mid 0.275042 0.275042)
							(end 0.2032 0.3048)
						)
						(arc
							(start -0.2032 0.3048)
							(mid -0.275042 0.275042)
							(end -0.3048 0.2032)
						)
						(arc
							(start -0.3048 -0.2032)
							(mid -0.275042 -0.275042)
							(end -0.2032 -0.3048)
						)
						(arc
							(start 0.2032 -0.3048)
							(mid 0.275042 -0.275042)
							(end 0.3048 -0.2032)
						)
					)
					(width 0)
					(fill yes)
				)
			)
		)
		(pad "2" smd custom
			(at 0 0.4445 90)
			(size 0.1524 0.1524)
			(layers "B.Cu" "B.Mask" "B.Paste")
			(net "AGND_P3V3_STBY")
			(options
				(clearance outline)
				(anchor circle)
			)
			(primitives
				(gr_poly
					(pts
						(arc
							(start 0.3048 0.2032)
							(mid 0.275042 0.275042)
							(end 0.2032 0.3048)
						)
						(arc
							(start -0.2032 0.3048)
							(mid -0.275042 0.275042)
							(end -0.3048 0.2032)
						)
						(arc
							(start -0.3048 -0.2032)
							(mid -0.275042 -0.275042)
							(end -0.2032 -0.3048)
						)
						(arc
							(start 0.2032 -0.3048)
							(mid 0.275042 -0.275042)
							(end 0.3048 -0.2032)
						)
					)
					(width 0)
					(fill yes)
				)
			)
		)
	)
	(footprint ""
		(layer "B.Cu")
		(at 18.161 -246.7864 180)
		(property "Reference" "C602"
			(at 0 0 0)
			(layer "B.SilkS")
			(hide yes)
			(effects
				(font
					(size 1.27 1.27)
				)
				(justify mirror)
			)
		)
		(property "Value" "SC10U16V5KX-7-GP-U"
			(at 0.0762 -6.1214 180)
			(unlocked yes)
			(layer "B.Fab")
			(hide yes)
			(effects
				(font
					(size 1.016 1.016)
					(thickness 0.1524)
				)
				(justify mirror)
			)
		)
		(property "Device Type" "C805H58"
			(at 0.0762 -8.1534 180)
			(unlocked yes)
			(layer "B.Fab")
			(hide yes)
			(effects
				(font
					(size 1.016 1.016)
					(thickness 0.1524)
				)
				(justify mirror)
			)
		)
		(duplicate_pad_numbers_are_jumpers no)
		(fp_line
			(start -0.635 0)
			(end 0.635 0)
			(stroke
				(width 0.508)
				(type default)
			)
			(layer "B.SilkS")
		)
		(fp_rect
			(start 0.9652 1.778)
			(end -0.9652 -1.778)
			(stroke
				(width 0)
				(type default)
			)
			(fill no)
			(layer "B.CrtYd")
		)
		(fp_poly
			(pts
				(xy 0.9652 -1.778) (xy -0.9652 -1.778) (xy -0.9652 1.778) (xy 0.9652 1.778)
			)
			(stroke
				(width 0)
				(type default)
			)
			(fill no)
			(layer "B.Fab")
		)
		(pad "1" smd rect
			(at 0 -0.9652)
			(size 1.397 1.143)
			(layers "B.Cu" "B.Mask" "B.Paste")
			(net "P12V_A_VIN_U20")
		)
		(pad "2" smd rect
			(at 0 0.9652)
			(size 1.397 1.143)
			(layers "B.Cu" "B.Mask" "B.Paste")
			(net "GND")
		)
	)
	(footprint ""
		(layer "B.Cu")
		(at 473.1512 -252.5522 180)
		(property "Reference" "C645"
			(at 0 0 0)
			(layer "B.SilkS")
			(hide yes)
			(effects
				(font
					(size 1.27 1.27)
				)
				(justify mirror)
			)
		)
		(property "Value" "SC10U16V5KX-7-GP-U"
			(at 0.0762 -6.1214 180)
			(unlocked yes)
			(layer "B.Fab")
			(hide yes)
			(effects
				(font
					(size 1.016 1.016)
					(thickness 0.1524)
				)
				(justify mirror)
			)
		)
		(property "Device Type" "C805H58"
			(at 0.0762 -8.1534 180)
			(unlocked yes)
			(layer "B.Fab")
			(hide yes)
			(effects
				(font
					(size 1.016 1.016)
					(thickness 0.1524)
				)
				(justify mirror)
			)
		)
		(duplicate_pad_numbers_are_jumpers no)
		(fp_line
			(start -0.635 0)
			(end 0.635 0)
			(stroke
				(width 0.508)
				(type default)
			)
			(layer "B.SilkS")
		)
		(fp_rect
			(start 0.9652 1.778)
			(end -0.9652 -1.778)
			(stroke
				(width 0)
				(type default)
			)
			(fill no)
			(layer "B.CrtYd")
		)
		(fp_poly
			(pts
				(xy 0.9652 -1.778) (xy -0.9652 -1.778) (xy -0.9652 1.778) (xy 0.9652 1.778)
			)
			(stroke
				(width 0)
				(type default)
			)
			(fill no)
			(layer "B.Fab")
		)
		(pad "1" smd rect
			(at 0 -0.9652)
			(size 1.397 1.143)
			(layers "B.Cu" "B.Mask" "B.Paste")
			(net "P5V_A_3")
		)
		(pad "2" smd rect
			(at 0 0.9652)
			(size 1.397 1.143)
			(layers "B.Cu" "B.Mask" "B.Paste")
			(net "GND")
		)
	)
	(footprint ""
		(layer "B.Cu")
		(at 362.6358 -142.7734 90)
		(property "Reference" "R1086"
			(at 0 0 90)
			(layer "B.SilkS")
			(hide yes)
			(effects
				(font
					(size 1.27 1.27)
				)
				(justify mirror)
			)
		)
		(property "Value" "10R2F-L-GP"
			(at -0.064008 -3.993896 90)
			(unlocked yes)
			(layer "B.Fab")
			(hide yes)
			(effects
				(font
					(size 1.016 1.016)
					(thickness 0.1524)
				)
				(justify mirror)
			)
		)
		(property "Device Type" "R402H14"
			(at -0.064008 -5.517896 90)
			(unlocked yes)
			(layer "B.Fab")
			(hide yes)
			(effects
				(font
					(size 1.016 1.016)
					(thickness 0.1524)
				)
				(justify mirror)
			)
		)
		(duplicate_pad_numbers_are_jumpers no)
		(fp_line
			(start 0.508 -0.9398)
			(end 0.508 0.9398)
			(stroke
				(width 0.1524)
				(type default)
			)
			(layer "B.SilkS")
		)
		(fp_line
			(start -0.508 -0.9398)
			(end 0.508 -0.9398)
			(stroke
				(width 0.1524)
				(type default)
			)
			(layer "B.SilkS")
		)
		(fp_rect
			(start 0.508 0.9398)
			(end -0.508 -0.9398)
			(stroke
				(width 0)
				(type default)
			)
			(fill no)
			(layer "B.CrtYd")
		)
		(fp_rect
			(start 0.508 0.9398)
			(end -0.508 -0.9398)
			(stroke
				(width 0)
				(type default)
			)
			(fill no)
			(layer "B.Fab")
		)
		(pad "1" smd custom
			(at 0 -0.4445 270)
			(size 0.1397 0.1397)
			(layers "B.Cu" "B.Mask" "B.Paste")
			(net "MB1_CM_SENSE_R1_P")
			(options
				(clearance outline)
				(anchor circle)
			)
			(primitives
				(gr_poly
					(pts
						(arc
							(start -0.1778 0.2794)
							(mid -0.249642 0.249642)
							(end -0.2794 0.1778)
						)
						(arc
							(start -0.2794 -0.1778)
							(mid -0.249642 -0.249642)
							(end -0.1778 -0.2794)
						)
						(arc
							(start 0.1778 -0.2794)
							(mid 0.249642 -0.249642)
							(end 0.2794 -0.1778)
						)
						(arc
							(start 0.2794 0.1778)
							(mid 0.249642 0.249642)
							(end 0.1778 0.2794)
						)
					)
					(width 0)
					(fill yes)
				)
			)
		)
		(pad "2" smd custom
			(at 0 0.4445 270)
			(size 0.1397 0.1397)
			(layers "B.Cu" "B.Mask" "B.Paste")
			(net "MB1_CM_SENSE_P")
			(options
				(clearance outline)
				(anchor circle)
			)
			(primitives
				(gr_poly
					(pts
						(arc
							(start -0.1778 0.2794)
							(mid -0.249642 0.249642)
							(end -0.2794 0.1778)
						)
						(arc
							(start -0.2794 -0.1778)
							(mid -0.249642 -0.249642)
							(end -0.1778 -0.2794)
						)
						(arc
							(start 0.1778 -0.2794)
							(mid 0.249642 -0.249642)
							(end 0.2794 -0.1778)
						)
						(arc
							(start 0.2794 0.1778)
							(mid 0.249642 0.249642)
							(end 0.1778 0.2794)
						)
					)
					(width 0)
					(fill yes)
				)
			)
		)
	)
	(footprint ""
		(layer "B.Cu")
		(at 38.490144 -252.901196 180)
		(property "Reference" "R1211"
			(at 0 0 0)
			(layer "B.SilkS")
			(hide yes)
			(effects
				(font
					(size 1.27 1.27)
				)
				(justify mirror)
			)
		)
		(property "Value" "2K7R2F-GP"
			(at -0.064008 -3.993896 180)
			(unlocked yes)
			(layer "B.Fab")
			(hide yes)
			(effects
				(font
					(size 1.016 1.016)
					(thickness 0.1524)
				)
				(justify mirror)
			)
		)
		(property "Device Type" "R402H16"
			(at -0.064008 -5.517896 180)
			(unlocked yes)
			(layer "B.Fab")
			(hide yes)
			(effects
				(font
					(size 1.016 1.016)
					(thickness 0.1524)
				)
				(justify mirror)
			)
		)
		(duplicate_pad_numbers_are_jumpers no)
		(fp_line
			(start 0.508 -0.9398)
			(end 0.508 0.9398)
			(stroke
				(width 0.1524)
				(type default)
			)
			(layer "B.SilkS")
		)
		(fp_line
			(start -0.508 -0.9398)
			(end 0.508 -0.9398)
			(stroke
				(width 0.1524)
				(type default)
			)
			(layer "B.SilkS")
		)
		(fp_rect
			(start 0.508 0.9398)
			(end -0.508 -0.9398)
			(stroke
				(width 0)
				(type default)
			)
			(fill no)
			(layer "B.CrtYd")
		)
		(fp_rect
			(start 0.508 0.9398)
			(end -0.508 -0.9398)
			(stroke
				(width 0)
				(type default)
			)
			(fill no)
			(layer "B.Fab")
		)
		(pad "1" smd custom
			(at 0 -0.4445)
			(size 0.1397 0.1397)
			(layers "B.Cu" "B.Mask" "B.Paste")
			(net "P5V_A_LL")
			(options
				(clearance outline)
				(anchor circle)
			)
			(primitives
				(gr_poly
					(pts
						(arc
							(start -0.1778 0.2794)
							(mid -0.249642 0.249642)
							(end -0.2794 0.1778)
						)
						(arc
							(start -0.2794 -0.1778)
							(mid -0.249642 -0.249642)
							(end -0.1778 -0.2794)
						)
						(arc
							(start 0.1778 -0.2794)
							(mid 0.249642 -0.249642)
							(end 0.2794 -0.1778)
						)
						(arc
							(start 0.2794 0.1778)
							(mid 0.249642 0.249642)
							(end 0.1778 0.2794)
						)
					)
					(width 0)
					(fill yes)
				)
			)
		)
		(pad "2" smd custom
			(at 0 0.4445)
			(size 0.1397 0.1397)
			(layers "B.Cu" "B.Mask" "B.Paste")
			(net "P5V_A_LL_R")
			(options
				(clearance outline)
				(anchor circle)
			)
			(primitives
				(gr_poly
					(pts
						(arc
							(start -0.1778 0.2794)
							(mid -0.249642 0.249642)
							(end -0.2794 0.1778)
						)
						(arc
							(start -0.2794 -0.1778)
							(mid -0.249642 -0.249642)
							(end -0.1778 -0.2794)
						)
						(arc
							(start 0.1778 -0.2794)
							(mid 0.249642 -0.249642)
							(end 0.2794 -0.1778)
						)
						(arc
							(start 0.2794 0.1778)
							(mid 0.249642 0.249642)
							(end 0.1778 0.2794)
						)
					)
					(width 0)
					(fill yes)
				)
			)
		)
	)
	(footprint ""
		(layer "B.Cu")
		(at 371.599968 -220.199966 180)
		(property "Reference" "NUT8"
			(at 0 0 0)
			(layer "B.SilkS")
			(hide yes)
			(effects
				(font
					(size 1.27 1.27)
				)
				(justify mirror)
			)
		)
		(property "Value" "STF256R168H278-GP"
			(at 4.826 0.0508 180)
			(unlocked yes)
			(layer "B.Fab")
			(hide yes)
			(effects
				(font
					(size 1.016 1.016)
					(thickness 0.1524)
				)
				(justify mirror)
			)
		)
		(property "Device Type" "STF256R168H278"
			(at 4.826 -1.4732 180)
			(unlocked yes)
			(layer "B.Fab")
			(hide yes)
			(effects
				(font
					(size 1.016 1.016)
					(thickness 0.1524)
				)
				(justify mirror)
			)
		)
		(duplicate_pad_numbers_are_jumpers no)
		(fp_circle
			(center 0 0)
			(end -3.6068 0)
			(stroke
				(width 0.3048)
				(type default)
			)
			(fill no)
			(layer "B.SilkS")
		)
		(fp_poly
			(pts
				(arc
					(start -2.5019 0)
					(mid 2.5019 0)
					(end -2.5019 0)
				)
			)
			(stroke
				(width 0)
				(type default)
			)
			(fill no)
			(layer "B.CrtYd")
		)
		(fp_poly
			(pts
				(arc
					(start -3.7592 0.00635)
					(mid 3.759205 0)
					(end -3.7592 -0.00635)
				)
				(arc
					(start -2.5019 -0.00635)
					(mid 2.501908 0)
					(end -2.5019 0.00635)
				)
			)
			(stroke
				(width 0)
				(type default)
			)
			(fill no)
			(layer "B.CrtYd")
		)
		(fp_poly
			(pts
				(arc
					(start -3.7592 0)
					(mid 3.7592 0)
					(end -3.7592 0)
				)
			)
			(stroke
				(width 0)
				(type default)
			)
			(fill no)
			(layer "F.CrtYd")
		)
		(fp_poly
			(pts
				(arc
					(start -3.7592 0)
					(mid 3.7592 0)
					(end -3.7592 0)
				)
			)
			(stroke
				(width 0)
				(type default)
			)
			(fill no)
			(layer "B.Fab")
		)
		(fp_poly
			(pts
				(arc
					(start -3.7592 0)
					(mid 3.7592 0)
					(end -3.7592 0)
				)
			)
			(stroke
				(width 0)
				(type default)
			)
			(fill no)
			(layer "F.Fab")
		)
		(pad "1" thru_hole circle
			(at 0 0)
			(size 6.5024 6.5024)
			(drill 4.2672)
			(layers "*.Cu" "*.Mask")
			(remove_unused_layers no)
			(net "Net_4")
			(clearance -0.6096)
			(padstack
				(mode front_inner_back)
				(layer "Inner"
					(shape circle)
					(size 4.6736 4.6736)
					(clearance 0.3048)
				)
				(layer "B.Cu"
					(shape circle)
					(size 6.5024 6.5024)
					(thermal_gap 0.3048)
					(clearance -0.6096)
				)
			)
		)
	)
	(footprint ""
		(layer "B.Cu")
		(at 470.408 -241.427 -90)
		(property "Reference" "C648"
			(at 0 0 90)
			(layer "B.SilkS")
			(hide yes)
			(effects
				(font
					(size 1.27 1.27)
				)
				(justify mirror)
			)
		)
		(property "Value" "SC10U16V5KX-7-GP-U"
			(at 0.0762 -6.1214 270)
			(unlocked yes)
			(layer "B.Fab")
			(hide yes)
			(effects
				(font
					(size 1.016 1.016)
					(thickness 0.1524)
				)
				(justify mirror)
			)
		)
		(property "Device Type" "C805H58"
			(at 0.0762 -8.1534 270)
			(unlocked yes)
			(layer "B.Fab")
			(hide yes)
			(effects
				(font
					(size 1.016 1.016)
					(thickness 0.1524)
				)
				(justify mirror)
			)
		)
		(duplicate_pad_numbers_are_jumpers no)
		(fp_line
			(start -0.635 0)
			(end 0.635 0)
			(stroke
				(width 0.508)
				(type default)
			)
			(layer "B.SilkS")
		)
		(fp_rect
			(start 0.9652 1.778)
			(end -0.9652 -1.778)
			(stroke
				(width 0)
				(type default)
			)
			(fill no)
			(layer "B.CrtYd")
		)
		(fp_poly
			(pts
				(xy 0.9652 -1.778) (xy -0.9652 -1.778) (xy -0.9652 1.778) (xy 0.9652 1.778)
			)
			(stroke
				(width 0)
				(type default)
			)
			(fill no)
			(layer "B.Fab")
		)
		(pad "1" smd rect
			(at 0 -0.9652 90)
			(size 1.397 1.143)
			(layers "B.Cu" "B.Mask" "B.Paste")
			(net "P12V_A_VIN_U27")
		)
		(pad "2" smd rect
			(at 0 0.9652 90)
			(size 1.397 1.143)
			(layers "B.Cu" "B.Mask" "B.Paste")
			(net "GND")
		)
	)
	(footprint ""
		(layer "B.Cu")
		(at 71.0946 -147.5486 180)
		(property "Reference" "C629"
			(at 0 0 0)
			(layer "B.SilkS")
			(hide yes)
			(effects
				(font
					(size 1.27 1.27)
				)
				(justify mirror)
			)
		)
		(property "Value" "SC10U16V5KX-7-GP-U"
			(at 0.0762 -6.1214 180)
			(unlocked yes)
			(layer "B.Fab")
			(hide yes)
			(effects
				(font
					(size 1.016 1.016)
					(thickness 0.1524)
				)
				(justify mirror)
			)
		)
		(property "Device Type" "C805H58"
			(at 0.0762 -8.1534 180)
			(unlocked yes)
			(layer "B.Fab")
			(hide yes)
			(effects
				(font
					(size 1.016 1.016)
					(thickness 0.1524)
				)
				(justify mirror)
			)
		)
		(duplicate_pad_numbers_are_jumpers no)
		(fp_line
			(start -0.635 0)
			(end 0.635 0)
			(stroke
				(width 0.508)
				(type default)
			)
			(layer "B.SilkS")
		)
		(fp_rect
			(start 0.9652 1.778)
			(end -0.9652 -1.778)
			(stroke
				(width 0)
				(type default)
			)
			(fill no)
			(layer "B.CrtYd")
		)
		(fp_poly
			(pts
				(xy 0.9652 -1.778) (xy -0.9652 -1.778) (xy -0.9652 1.778) (xy 0.9652 1.778)
			)
			(stroke
				(width 0)
				(type default)
			)
			(fill no)
			(layer "B.Fab")
		)
		(pad "1" smd rect
			(at 0 -0.9652)
			(size 1.397 1.143)
			(layers "B.Cu" "B.Mask" "B.Paste")
			(net "P5V_A_2")
		)
		(pad "2" smd rect
			(at 0 0.9652)
			(size 1.397 1.143)
			(layers "B.Cu" "B.Mask" "B.Paste")
			(net "GND")
		)
	)
	(footprint ""
		(layer "B.Cu")
		(at 220.188028 -103.2637 -90)
		(property "Reference" "C529"
			(at 0 0 90)
			(layer "B.SilkS")
			(hide yes)
			(effects
				(font
					(size 1.27 1.27)
				)
				(justify mirror)
			)
		)
		(property "Value" "SC22U25V6KX-2-GP-U"
			(at 2.860802 -5.279644 270)
			(unlocked yes)
			(layer "B.Fab")
			(hide yes)
			(effects
				(font
					(size 1.016 1.016)
					(thickness 0.1524)
				)
				(justify mirror)
			)
		)
		(property "Device Type" "C1206-TO0D3H75"
			(at 2.860802 -6.803644 270)
			(unlocked yes)
			(layer "B.Fab")
			(hide yes)
			(effects
				(font
					(size 1.016 1.016)
					(thickness 0.1524)
				)
				(justify mirror)
			)
		)
		(duplicate_pad_numbers_are_jumpers no)
		(fp_line
			(start -1.3081 2.3749)
			(end 1.3081 2.3749)
			(stroke
				(width 0.1524)
				(type default)
			)
			(layer "B.SilkS")
		)
		(fp_line
			(start 1.3081 2.3749)
			(end 1.3081 -2.3749)
			(stroke
				(width 0.1524)
				(type default)
			)
			(layer "B.SilkS")
		)
		(fp_line
			(start -1.3081 -2.3749)
			(end -1.3081 2.3749)
			(stroke
				(width 0.1524)
				(type default)
			)
			(layer "B.SilkS")
		)
		(fp_line
			(start 1.3081 -2.3749)
			(end -1.3081 -2.3749)
			(stroke
				(width 0.1524)
				(type default)
			)
			(layer "B.SilkS")
		)
		(fp_rect
			(start 0.8001 1.6002)
			(end -0.8001 -1.6002)
			(stroke
				(width 0)
				(type default)
			)
			(fill no)
			(layer "B.CrtYd")
		)
		(fp_poly
			(pts
				(xy 1.5621 2.4511) (xy 1.5621 1.6002) (xy -0.8001 1.6002) (xy -0.8001 -1.6002) (xy 0.8001 -1.6002)
				(xy 0.8001 1.5875) (xy 1.5621 1.5875) (xy 1.5621 -2.4511) (xy -1.5621 -2.4511) (xy -1.5621 2.4511)
			)
			(stroke
				(width 0)
				(type default)
			)
			(fill no)
			(layer "B.CrtYd")
		)
		(fp_rect
			(start 1.5621 2.4511)
			(end -1.5621 -2.4511)
			(stroke
				(width 0)
				(type default)
			)
			(fill no)
			(layer "B.Fab")
		)
		(pad "1" smd rect
			(at 0 -1.392936 90)
			(size 2.1082 1.4478)
			(layers "B.Cu" "B.Mask" "B.Paste")
			(net "P12V_A_COMP")
		)
		(pad "2" smd rect
			(at 0 1.392936 90)
			(size 2.1082 1.4478)
			(layers "B.Cu" "B.Mask" "B.Paste")
			(net "GND")
		)
	)
)
